FILE_TYPE = CONNECTIVITY;
{Allegro Design Entry HDL 17.2-2016 S081 (4005846) 1/11/2022}
"PAGE_NUMBER" = 15;
0"NC";
1"P3V3_RGM\g";
2"P1V8_AUX\g";
3"P3V3_P1V8_SD1VDD\g";
4"P1V8_AUX\g";
5"P3V3_AUX\g";
6"P3V3_AUX\g";
7"P3V3_P1V8_SD2VDD\g";
8"P3V3_AUX\g";
9"P1V8_AUX\g";
10"P3V3_AUX\g";
11"P3V3_RGM\g";
12"P3V3_RGM\g";
13"P3V3_RGM\g";
14"P1V2_AUX\g";
15"P1V0_AUX\g";
16"P12V_AUX\g";
17"P5V_AUX\g";
18"P3V3_AUX\g";
19"P2V5_AUX\g";
20"PGPPA_BMC_AUX\g";
21"P1V8_AUX\g";
22"P3V3_AUX\g";
23"GND\g";
24"GND\g";
25"GND\g";
26"GND\g";
27"GND\g";
28"GND\g";
29"GND\g";
30"GND\g";
31"GND\g";
32"GND\g";
33"GND\g";
34"GND\g";
35"GND\g";
36"GND\g";
37"GND\g";
38"GND\g";
39"GND\g";
40"GND\g";
41"GND\g";
42"GND\g";
43"GND\g";
44"GND\g";
45"GND\g";
46"P3V_BAT_SENSOR";
47"PGPPA_BMC_AUX_SENSOR";
48"BATTERY_DETECT_R";
49"BMC_CLK_25M_R";
50"PWR_BTN_BMC_N";
51"PU_25M_BMC_CLK_EN";
52"P5V_SENSOR";
53"P12V_SENSOR";
54"P1V0_SENSOR";
55"P1V2_SENSOR";
56"JTAG_1_BMC_TDO";
57"P1V8_SENSOR";
58"JTAG_SCM_TMS";
59"BMC_CLK_25M";
60"RST_EXTRST_N";
61"RST_BMC_SRST_N";
62"P3V_BAT_R1";
63"P3V3_BMC_USB2AV33";
64"P3V3_BMC_USB2AV33";
65"V_DACB_R";
66"SYS_PWRBTN_N";
67"JTAG_SCM_TDO";
68"PGPPA_BMC_AUX_SENSOR";
69"FM_PCH_BEEP_LED";
70"FM_P12V_HSC_ENABLE_R1";
71"FM_HDD_LED_N";
72"GPU_WP_HW_CTRL_R_N";
73"GPU_NVS_PWR_BRAKE_R_N";
74"IRQ_PCH_TPM_SPI_N";
75"USB_OC0_REAR_R_N";
76"SMB_BMC_ALERT9_N";
77"SMB_BMC_ALERT10_N";
78"P3V3_SENSOR";
79"P2V5_SENSOR";
80"P1V8_SENSOR";
81"PECI_BMC";
82"V_DACG_R";
83"P1V8_BMC_USB2AV18";
84"SYS_BMC_PWRBTN_R_N";
85"BMC_CLK_25M";
86"P3V_BAT_R";
87"JTAG_1_BMC_TDO_R";
88"SMB_BMC_ALERT16_N";
89"BSM_PRSNT_R_N";
90"P1V0_SENSOR";
91"SMB_BMC_ALERT10_R_N";
92"SMB_BMC_ALERT9_R_N";
93"IRQ_OC_DETECT_EN_N";
94"IRQ_UV_DETECT_N";
95"IRQ_OC_DETECT_N";
96"FM_SOL_UART_CH_SEL_R1";
97"PWRGD_CPUPWRGD_LVC1";
98"PWRGD_PCH_PWROK";
99"IRQ_CPU1_VRHOT_N";
100"P5V_SENSOR";
101"FM_SOL_UART_CH_SEL";
102"FM_P12V_HSC_ENABLE";
103"RST_EXTRST_N";
104"RST_BMC_SRST_N";
105"P3V_BAT_SENSOR";
106"P1V2_SENSOR";
107"V_VGAHS_R";
108"V_VGAVS_R";
109"FM_ADR_COMPLETE";
110"FM_SPD_REMOTE_EN_R";
111"H_CPU1_MEMTRIP_LVC1_N";
112"BMC_HEARTBEAT_N";
113"USB_HOST_BMC_B_R_DN";
114"PECI_BMC_R";
115"JTAG_SCM_TCK";
116"JTAG_SCM_NTRST";
117"FM_PCHHOT_R_N";
118"FM_BMC_EN_DET_R";
119"SMB_BMC_ALERT12_N";
120"P2V5_SENSOR";
121"P3V3_SENSOR";
122"P12V_SENSOR";
123"FM_BIOS_POST_CMPLT_BMC_N";
124"FM_BMC_SSPRST_N";
125"RST_SPI_FLASH_N";
126"PD_SP_ENTEST";
127"BMC_RSTIND_N";
128"IRQ_CPU0_VRHOT_N";
129"PECI_BMC";
130"RST_BMC_RSTBTN_OUT_N";
131"V_DACR_R";
132"SYS_BMC_PWRBTN_R1_N";
133"FM_JTAG_BMC_MUX_SEL";
134"FM_INTRUDER_R_N";
135"FM_INTRUDER_N";
136"JTAG_1_BMC_TDI_R";
137"JTAG_1_BMC_TMS_R";
138"JTAG_1_BMC_TCK_R";
139"JTAG_1_BMC_TRST_R";
140"SYS_BMC_PWRBTN_R_N";
141"PWR_BTN_BMC_N";
142"ID_RST_BTN_BMC_N";
143"PWR_LED";
144"RST_BMC_RSTBTN_OUT_N";
145"USB_HOST_BMC_A_DP";
146"USB_HOST_BMC_A_DN";
147"USB_HOST_BMC_B_DP";
148"USB_HOST_BMC_B_DN";
149"JTAG_SCM_TDI";
150"PVCCIO_PECI_BMC";
151"USB_HOST_BMC_B_R_DP";
152"USB_HOST_BMC_A_R_DN";
153"USB_HOST_BMC_A_R_DP";
154"P1V8_BMC_USB2AV18";
155"H_CPU0_MEMTRIP_LVC1_N";
156"BMC_PWR_LED";
157"RST_BMC_RSTBTN_OUT_R_N";
158"ID_RST_BTN_BMC_R_N";
159"SYS_BMC_PWRBTN_R1_N";
160"FM_PWR_BTN";
161"FM_TPM_PRSNT_0_N";
162"FM_ADR_TRIGGER_N";
163"FM_JTAG_BMC_MUX_SEL_R1";
164"FM_PCIE_M2_SSD0_PRSNT_N";
165"V_BMC_DDC_SCL";
166"FM_PMBUS_ALERT_EN";
167"V_BMC_DDC_SDA";
168"V_VGAVS";
169"V_VGAHS";
170"V_DACR";
171"V_DACB";
172"V_DACG";
173"V_DACB_R";
174"V_DACR_R";
175"V_DACG_R";
176"BATTERY_DETECT";
%"UNIVERSAL_POWER"
"1","(1850,-700)","0","logical_power","I1";
;
HDL_POWER"P1V8_AUX"
CDS_LIB"logical_power";
"A"4;
%"Q_CAP"
"1","(4450,2375)","0","pure_quanta","I117";
;
VALUE"22UF"
TOLERANCE"20%"
MATERIAL"X6S"
VOLTAGE"6.3V"
PACK_TYPE"C0603"
PART_NUMBER"CH6221ME900"
CDS_LIB"pure_quanta"
LOCATION"C42"
$SEC"1"
CDS_SEC"1";
"B"
$PN"2"26;
"A"
$PN"1"150;
%"UNIVERSAL_GND"
"1","(4625,2100)","0","logical_power","I118";
;
HDL_POWER"GND"
CDS_LIB"logical_power";
"A"26;
%"Q_CAP"
"1","(4675,2375)","0","pure_quanta","I119";
;
MATERIAL"X6S"
TOLERANCE"10%"
PACK_TYPE"C0402"
PART_NUMBER"CH5104KEB02"
VOLTAGE"25V"
VALUE"1UF"
CDS_LIB"pure_quanta"
LOCATION"C43"
$SEC"1"
CDS_SEC"1";
"B"
$PN"2"26;
"A"
$PN"1"150;
%"Q_RES"
"1","(4125,3325)","0","pure_quanta","I128";
;
VALUE"0"
MATERIAL"CHIP"
PART_NUMBER"CS00002JB13"
PACK_TYPE"0402LF"
WATTAGE"1/16W"
TOLERANCE"5%"
CDS_LIB"pure_quanta"
LOCATION"R566"
$SEC"1"
CDS_SEC"1";
"B"
$PN"2"144;
"A"
$PN"1"157;
%"Q_RES"
"1","(3000,4275)","0","pure_quanta","I133";
;
VALUE"10"
MATERIAL"CHIP"
PACK_TYPE"0402LF"
WATTAGE"1/16W"
CDS_LIB"pure_quanta"
TOLERANCE"1%"
PART_NUMBER"CS01002FB07"
LOCATION"R21"
$SEC"1"
CDS_SEC"1";
"B"
$PN"2"172;
"A"
$PN"1"175;
%"Q_RES"
"1","(3000,4325)","0","pure_quanta","I134";
;
WATTAGE"1/16W"
PACK_TYPE"0402LF"
VALUE"10"
MATERIAL"CHIP"
PART_NUMBER"CS01002FB07"
TOLERANCE"1%"
CDS_LIB"pure_quanta"
LOCATION"R24"
$SEC"1"
CDS_SEC"1";
"B"
$PN"2"171;
"A"
$PN"1"173;
%"Q_CAP"
"1","(3175,-725)","0","pure_quanta","I14";
;
TOLERANCE"10%"
VOLTAGE"25V"
PACK_TYPE"C0402"
MATERIAL"X6S"
VALUE"1UF"
CDS_LIB"pure_quanta"
PART_NUMBER"CH5104KEB02"
LOCATION"C35"
$SEC"1"
CDS_SEC"1";
"B"
$PN"2"29;
"A"
$PN"1"3;
%"Q_RES"
"1","(2975,4075)","0","pure_quanta","I140";
;
MATERIAL"CHIP"
VALUE"0"
PART_NUMBER"CS00002JB13"
PACK_TYPE"0402LF"
WATTAGE"1/16W"
TOLERANCE"5%"
CDS_LIB"pure_quanta"
LOCATION"R20"
$SEC"1"
CDS_SEC"1";
"B"
$PN"2"168;
"A"
$PN"1"108;
%"Q_RES"
"1","(2975,4125)","0","pure_quanta","I141";
;
VALUE"0"
MATERIAL"CHIP"
PART_NUMBER"CS00002JB13"
PACK_TYPE"0402LF"
WATTAGE"1/16W"
TOLERANCE"5%"
CDS_LIB"pure_quanta"
LOCATION"R19"
$SEC"1"
CDS_SEC"1";
"B"
$PN"2"169;
"A"
$PN"1"107;
%"Q_RES"
"1","(3000,4225)","0","pure_quanta","I142";
;
VALUE"10"
MATERIAL"CHIP"
PART_NUMBER"CS01002FB07"
TOLERANCE"1%"
CDS_LIB"pure_quanta"
WATTAGE"1/16W"
PACK_TYPE"0402LF"
LOCATION"R26"
$SEC"1"
CDS_SEC"1";
"B"
$PN"2"170;
"A"
$PN"1"174;
%"UNIVERSAL_GND"
"1","(6100,4025)","0","logical_power","I148";
;
HDL_POWER"GND"
CDS_LIB"logical_power";
"A"45;
%"Q_RES"
"1","(5600,4175)","0","pure_quanta","I149";
;
VALUE"150"
MATERIAL"CHIP"
PART_NUMBER"CS11502FB07"
PACK_TYPE"0402LF"
WATTAGE"1/16W"
TOLERANCE"1%"
CDS_LIB"pure_quanta"
LOCATION"R25"
$SEC"1"
CDS_SEC"1";
"B"
$PN"2"45;
"A"
$PN"1"131;
%"UNIVERSAL_GND"
"1","(3250,-1000)","0","logical_power","I15";
;
HDL_POWER"GND"
CDS_LIB"logical_power";
"A"29;
%"Q_RES"
"1","(5600,4275)","0","pure_quanta","I150";
;
VALUE"150"
MATERIAL"CHIP"
PART_NUMBER"CS11502FB07"
PACK_TYPE"0402LF"
WATTAGE"1/16W"
TOLERANCE"1%"
CDS_LIB"pure_quanta"
LOCATION"R23"
$SEC"1"
CDS_SEC"1";
"B"
$PN"2"45;
"A"
$PN"1"82;
%"Q_RES"
"1","(5600,4375)","0","pure_quanta","I151";
;
WATTAGE"1/16W"
PART_NUMBER"CS11502FB07"
VALUE"150"
PACK_TYPE"0402LF"
MATERIAL"CHIP"
TOLERANCE"1%"
CDS_LIB"pure_quanta"
LOCATION"R22"
$SEC"1"
CDS_SEC"1";
"B"
$PN"2"45;
"A"
$PN"1"65;
%"Q_RES"
"2","(-2900,4275)","0","pure_quanta","I152";
;
VALUE"4.7K"
TOLERANCE"1%"
MATERIAL"EMPTY"
PART_NUMBER"CS24702FB06"
PACK_TYPE"0402LF"
WATTAGE"1/16W"
CDS_LIB"pure_quanta"
LOCATION"R623"
$SEC"1"
CDS_SEC"1";
"A"
$PN"1"12;
"B"
$PN"2"103;
%"UNIVERSAL_POWER"
"1","(-2900,4500)","0","logical_power","I154";
;
HDL_POWER"P3V3_RGM"
CDS_LIB"logical_power";
"A"12;
%"Q_CAP"
"1","(3375,-725)","0","pure_quanta","I16";
;
PACK_TYPE"0402"
PART_NUMBER"CH4104K1B00"
VALUE"0.1UF"
VOLTAGE"25V"
TOLERANCE"10%"
MATERIAL"X7R"
CDS_LIB"pure_quanta"
LOCATION"C36"
$SEC"1"
CDS_SEC"1";
"B"
$PN"2"29;
"A"
$PN"1"3;
%"Q_RES"
"1","(3300,2625)","0","pure_quanta","I168";
;
VALUE"0"
MATERIAL"CHIP"
PART_NUMBER"CS00002JB13"
PACK_TYPE"0402LF"
WATTAGE"1/16W"
TOLERANCE"5%"
CDS_LIB"pure_quanta"
LOCATION"R528"
$SEC"1"
CDS_SEC"1";
"B"
$PN"2"148;
"A"
$PN"1"113;
%"Q_RES"
"1","(3300,2675)","0","pure_quanta","I169";
;
VALUE"0"
MATERIAL"CHIP"
CDS_LIB"pure_quanta"
TOLERANCE"5%"
WATTAGE"1/16W"
PACK_TYPE"0402LF"
PART_NUMBER"CS00002JB13"
LOCATION"R527"
$SEC"1"
CDS_SEC"1";
"B"
$PN"2"147;
"A"
$PN"1"151;
%"UNIVERSAL_GND"
"1","(5950,-1400)","0","logical_power","I17";
;
HDL_POWER"GND"
CDS_LIB"logical_power";
"A"30;
%"Q_RES"
"1","(4425,4000)","0","pure_quanta","I174";
;
VALUE"4.7K"
MATERIAL"CHIP"
TOLERANCE"1%"
WATTAGE"1/16W"
PACK_TYPE"0402LF"
PART_NUMBER"CS24702FB06"
CDS_LIB"pure_quanta"
LOCATION"R717"
$SEC"1"
CDS_SEC"1";
"B"
$PN"2"130;
"A"
$PN"1"5;
%"VCCAUX15"
"1","(4225,4125)","0","logical_power","I175";
;
HDL_POWER"P3V3_AUX"
CDS_LIB"logical_power";
"A"5;
%"MOSFET_N_GSD"
"1","(625,-700)","0","pure_quanta","I179";
;
PART_NUMBER"BAM70020062"
VALUE"NX7002AK"
PART_TYPE"SMLF"
MATERIAL"IC"
CDS_LIB"pure_quanta"
NEEDS_NO_SIZE"TRUE"
CDS_LMAN_SYM_OUTLINE"-100,100,100,-100"
LOCATION"Q11"
$SEC"1"
CDS_SEC"1";
"DRAIN"
$PN"D"62;
"SOURCE"
$PN"S"46;
"GATE"
$PN"G"48;
%"UNIVERSAL_POWER"
"1","(3625,-300)","0","logical_power","I18";
;
HDL_POWER"P3V3_P1V8_SD1VDD"
CDS_LIB"logical_power";
"A"3;
%"Q_CAP"
"1","(1100,-1250)","0","pure_quanta","I180";
;
PACK_TYPE"0402"
VALUE"100PF"
MATERIAL"NPO"
PART_NUMBER"CH11006JB00"
TOLERANCE"5%"
VOLTAGE"50V"
CDS_LIB"pure_quanta"
LOCATION"C275"
$SEC"1"
CDS_SEC"1";
"B"
$PN"2"31;
"A"
$PN"1"46;
%"Q_RES"
"2","(650,-1250)","0","pure_quanta","I181";
;
PART_NUMBER"CS41002FB09"
MATERIAL"CHIP"
WATTAGE"1/16W"
VALUE"100K"
PACK_TYPE"0402LF"
TOLERANCE"1%"
CDS_LIB"pure_quanta"
LOCATION"R778"
$SEC"1"
CDS_SEC"1";
"A"
$PN"1"46;
"B"
$PN"2"31;
%"Q_RES"
"1","(-400,-750)","0","pure_quanta","I183";
;
PART_NUMBER"CS21002FB06"
WATTAGE"1/16W"
MATERIAL"CHIP"
TOLERANCE"1%"
VALUE"1K"
PACK_TYPE"0402LF"
CDS_LIB"pure_quanta"
LOCATION"R775"
$SEC"1"
CDS_SEC"1";
"B"
$PN"2"48;
"A"
$PN"1"176;
%"Q_RES"
"2","(250,-1100)","0","pure_quanta","I184";
;
PACK_TYPE"0402LF"
PART_NUMBER"CS34702FB01"
VALUE"47K"
TOLERANCE"1%"
WATTAGE"1/16W"
MATERIAL"CHIP"
SEC_TYPE"0402LF"
CDS_LIB"pure_quanta"
LOCATION"R776"
SEC"1";
"A"
$PN"1"48;
"B"
$PN"2"32;
%"UNIVERSAL_GND"
"1","(650,-1550)","0","logical_power","I188";
;
HDL_POWER"GND"
CDS_LIB"logical_power";
"A"31;
%"UNIVERSAL_GND"
"1","(250,-1325)","0","logical_power","I189";
;
HDL_POWER"GND"
CDS_LIB"logical_power";
"A"32;
%"Q_RES"
"1","(5700,-1150)","0","pure_quanta","I19";
;
PART_NUMBER"CS31002FB08"
VALUE"10K"
MATERIAL"EMPTY"
CDS_LIB"pure_quanta"
TOLERANCE"1%"
WATTAGE"1/16W"
PACK_TYPE"0402LF"
LOCATION"R209"
$SEC"1"
CDS_SEC"1";
"B"
$PN"2"30;
"A"
$PN"1"81;
%"UNIVERSAL_POWER"
"1","(-2625,3675)","0","logical_power","I194";
;
HDL_POWER"P12V_AUX"
CDS_LIB"logical_power";
"A"16;
%"VCCAUX15"
"1","(-2625,2725)","0","logical_power","I195";
;
HDL_POWER"P5V_AUX"
CDS_LIB"logical_power";
"A"17;
%"VCCAUX15"
"1","(-2625,600)","0","logical_power","I196";
;
HDL_POWER"P2V5_AUX"
CDS_LIB"logical_power";
"A"19;
%"VCCAUX15"
"1","(-1650,1625)","0","logical_power","I197";
;
HDL_POWER"P1V2_AUX"
CDS_LIB"logical_power";
"A"14;
%"VCCAUX15"
"1","(-1625,525)","0","logical_power","I199";
;
HDL_POWER"P1V0_AUX"
CDS_LIB"logical_power";
"A"15;
%"Q_RES"
"1","(2425,-850)","0","pure_quanta","I2";
;
VALUE"0"
MATERIAL"EMPTY"
PART_NUMBER"CS00002JB13"
PACK_TYPE"0402LF"
WATTAGE"1/16W"
TOLERANCE"5%"
CDS_LIB"pure_quanta"
LOCATION"R208"
$SEC"1"
CDS_SEC"1";
"B"
$PN"2"3;
"A"
$PN"1"4;
%"VCCAUX15"
"1","(-2625,-500)","0","logical_power","I200";
;
HDL_POWER"P1V8_AUX"
CDS_LIB"logical_power";
"A"21;
%"Q_CAP"
"1","(-2425,3100)","0","pure_quanta","I201";
;
TOLERANCE"10%"
PACK_TYPE"0402"
MATERIAL"X7R"
PART_NUMBER"CH4104K1B00"
VOLTAGE"25V"
VALUE"0.1UF"
CDS_LIB"pure_quanta"
LOCATION"C290"
$SEC"1"
CDS_SEC"1";
"B"
$PN"2"28;
"A"
$PN"1"53;
%"Q_RES"
"2","(-2625,3475)","2","pure_quanta","I202";
;
PART_NUMBER"CS31582FB02"
PACK_TYPE"0402LF"
WATTAGE"1/16W"
TOLERANCE"1%"
VALUE"15.8K"
MATERIAL"CHIP"
CDS_LIB"pure_quanta"
LOCATION"R785"
$SEC"1"
CDS_SEC"1";
"A"
$PN"1"16;
"B"
$PN"2"53;
%"Q_RES"
"2","(-2625,3100)","2","pure_quanta","I203";
;
PART_NUMBER"CS22002FB07"
PACK_TYPE"0402LF"
MATERIAL"CHIP"
VALUE"2K"
WATTAGE"1/16W"
TOLERANCE"1%"
CDS_LIB"pure_quanta"
LOCATION"R786"
$SEC"1"
CDS_SEC"1";
"A"
$PN"1"53;
"B"
$PN"2"28;
%"UNIVERSAL_GND"
"1","(-2625,2825)","0","logical_power","I204";
;
HDL_POWER"GND"
CDS_LIB"logical_power";
"A"28;
%"Q_CAP"
"1","(-2425,2150)","0","pure_quanta","I207";
;
PART_NUMBER"CH4104K1B00"
PACK_TYPE"0402"
TOLERANCE"10%"
VALUE"0.1UF"
MATERIAL"X7R"
VOLTAGE"25V"
CDS_LIB"pure_quanta"
LOCATION"C295"
$SEC"1"
CDS_SEC"1";
"B"
$PN"2"33;
"A"
$PN"1"52;
%"Q_RES"
"2","(-500,625)","0","pure_quanta","I21";
;
MATERIAL"CHIP"
VALUE"4.7K"
TOLERANCE"1%"
WATTAGE"1/16W"
PACK_TYPE"0402LF"
PART_NUMBER"CS24702FB06"
CDS_LIB"pure_quanta"
LOCATION"R212"
$SEC"1"
CDS_SEC"1";
"A"
$PN"1"1;
"B"
$PN"2"51;
%"Q_RES"
"2","(-2625,2150)","2","pure_quanta","I211";
;
PART_NUMBER"CS22002FB07"
PACK_TYPE"0402LF"
VALUE"2K"
TOLERANCE"1%"
WATTAGE"1/16W"
MATERIAL"CHIP"
CDS_LIB"pure_quanta"
LOCATION"R788"
$SEC"1"
CDS_SEC"1";
"A"
$PN"1"52;
"B"
$PN"2"33;
%"UNIVERSAL_GND"
"1","(-2625,1875)","0","logical_power","I212";
;
HDL_POWER"GND"
CDS_LIB"logical_power";
"A"33;
%"Q_CAP"
"1","(-2425,1150)","0","pure_quanta","I215";
;
TOLERANCE"10%"
VALUE"0.1UF"
MATERIAL"X7R"
VOLTAGE"25V"
PACK_TYPE"0402"
PART_NUMBER"CH4104K1B00"
CDS_LIB"pure_quanta"
LOCATION"C299"
$SEC"1"
CDS_SEC"1";
"B"
$PN"2"34;
"A"
$PN"1"78;
%"UNIVERSAL_GND"
"1","(-2625,875)","0","logical_power","I216";
;
HDL_POWER"GND"
CDS_LIB"logical_power";
"A"34;
%"Q_RES"
"2","(-2625,1525)","2","pure_quanta","I219";
;
PART_NUMBER"CS22872FB03"
MATERIAL"CHIP"
WATTAGE"1/16W"
PACK_TYPE"0402LF"
VALUE"2.87K"
TOLERANCE"1%"
CDS_LIB"pure_quanta"
LOCATION"R789"
$SEC"1"
CDS_SEC"1";
"A"
$PN"1"18;
"B"
$PN"2"78;
%"UNIVERSAL_POWER"
"1","(-500,950)","0","logical_power","I22";
;
HDL_POWER"P3V3_RGM"
CDS_LIB"logical_power";
"A"1;
%"Q_RES"
"2","(-2625,1150)","2","pure_quanta","I220";
;
PACK_TYPE"0402LF"
PART_NUMBER"CS22002FB07"
VALUE"2K"
MATERIAL"CHIP"
TOLERANCE"1%"
WATTAGE"1/16W"
CDS_LIB"pure_quanta"
LOCATION"R790"
$SEC"1"
CDS_SEC"1";
"A"
$PN"1"78;
"B"
$PN"2"34;
%"UNIVERSAL_POWER"
"1","(-2625,1725)","0","logical_power","I221";
;
HDL_POWER"P3V3_AUX"
CDS_LIB"logical_power";
"A"18;
%"Q_RES"
"2","(-2625,2525)","2","pure_quanta","I223";
;
WATTAGE"1/16W"
MATERIAL"CHIP"
TOLERANCE"1%"
VALUE"5.36K"
PART_NUMBER"CS25362FB02"
PACK_TYPE"0402LF"
CDS_LIB"pure_quanta"
LOCATION"R787"
$SEC"1"
CDS_SEC"1";
"A"
$PN"1"17;
"B"
$PN"2"52;
%"UNIVERSAL_GND"
"1","(-175,500)","0","logical_power","I23";
;
HDL_POWER"GND"
CDS_LIB"logical_power";
"A"35;
%"Q_CAP"
"1","(-2425,25)","0","pure_quanta","I235";
;
TOLERANCE"10%"
PACK_TYPE"0402"
MATERIAL"X7R"
VALUE"0.1UF"
VOLTAGE"25V"
PART_NUMBER"CH4104K1B00"
CDS_LIB"pure_quanta"
LOCATION"C303"
$SEC"1"
CDS_SEC"1";
"B"
$PN"2"36;
"A"
$PN"1"79;
%"Q_RES"
"2","(-2625,25)","2","pure_quanta","I236";
;
PART_NUMBER"CS22002FB07"
PACK_TYPE"0402LF"
MATERIAL"CHIP"
TOLERANCE"1%"
VALUE"2K"
WATTAGE"1/16W"
CDS_LIB"pure_quanta"
LOCATION"R792"
$SEC"1"
CDS_SEC"1";
"A"
$PN"1"79;
"B"
$PN"2"36;
%"UNIVERSAL_GND"
"1","(-2625,-250)","0","logical_power","I237";
;
HDL_POWER"GND"
CDS_LIB"logical_power";
"A"36;
%"Q_CAP"
"1","(-175,800)","0","pure_quanta","I24";
;
VALUE"0.1UF"
PACK_TYPE"0402"
MATERIAL"X7R"
TOLERANCE"10%"
VOLTAGE"25V"
CDS_LIB"pure_quanta"
PART_NUMBER"CH4104K1B00"
LOCATION"C37"
$SEC"1"
CDS_SEC"1";
"B"
$PN"2"35;
"A"
$PN"1"13;
%"Q_CAP"
"1","(-2425,-1075)","0","pure_quanta","I240";
;
TOLERANCE"10%"
PACK_TYPE"0402"
MATERIAL"X7R"
VOLTAGE"25V"
VALUE"0.1UF"
PART_NUMBER"CH4104K1B00"
CDS_LIB"pure_quanta"
LOCATION"C307"
$SEC"1"
CDS_SEC"1";
"B"
$PN"2"37;
"A"
$PN"1"80;
%"Q_RES"
"2","(-2625,-1075)","2","pure_quanta","I242";
;
WATTAGE"1/16W"
PACK_TYPE"0402LF"
MATERIAL"CHIP"
TOLERANCE"1%"
VALUE"2K"
PART_NUMBER"CS22002FB07"
CDS_LIB"pure_quanta"
LOCATION"R794"
$SEC"1"
CDS_SEC"1";
"A"
$PN"1"80;
"B"
$PN"2"37;
%"UNIVERSAL_GND"
"1","(-2625,-1350)","0","logical_power","I243";
;
HDL_POWER"GND"
CDS_LIB"logical_power";
"A"37;
%"Q_RES"
"2","(-2625,-700)","2","pure_quanta","I244";
;
PART_NUMBER"CS16652FB00"
PACK_TYPE"0402LF"
MATERIAL"CHIP"
VALUE"665"
TOLERANCE"1%"
WATTAGE"1/16W"
CDS_LIB"pure_quanta"
LOCATION"R793"
$SEC"1"
CDS_SEC"1";
"A"
$PN"1"21;
"B"
$PN"2"80;
%"Q_RES"
"2","(-2625,400)","2","pure_quanta","I245";
;
PART_NUMBER"CS21692FB04"
PACK_TYPE"0402LF"
TOLERANCE"1%"
VALUE"1.69K"
WATTAGE"1/16W"
MATERIAL"CHIP"
CDS_LIB"pure_quanta"
LOCATION"R791"
$SEC"1"
CDS_SEC"1";
"A"
$PN"1"19;
"B"
$PN"2"79;
%"Q_CAP"
"1","(-1650,1025)","0","pure_quanta","I247";
;
PART_NUMBER"CH4104K1B00"
MATERIAL"X7R"
TOLERANCE"10%"
VALUE"0.1UF"
VOLTAGE"25V"
PACK_TYPE"0402"
CDS_LIB"pure_quanta"
LOCATION"C309"
$SEC"1"
CDS_SEC"1";
"B"
$PN"2"38;
"A"
$PN"1"55;
%"UNIVERSAL_POWER"
"1","(-175,1150)","0","logical_power","I25";
;
HDL_POWER"P3V3_RGM"
CDS_LIB"logical_power";
"A"13;
%"UNIVERSAL_GND"
"1","(-1650,750)","0","logical_power","I251";
;
HDL_POWER"GND"
CDS_LIB"logical_power";
"A"38;
%"Q_RES"
"2","(-1650,1425)","0","pure_quanta","I252";
;
TOLERANCE"1%"
VALUE"1K"
MATERIAL"CHIP"
WATTAGE"1/16W"
PACK_TYPE"0402LF"
PART_NUMBER"CS21002FB06"
CDS_LIB"pure_quanta"
LOCATION"R795"
$SEC"1"
CDS_SEC"1";
"A"
$PN"1"14;
"B"
$PN"2"55;
%"Q_RES"
"2","(-1625,325)","0","pure_quanta","I255";
;
VALUE"1K"
TOLERANCE"1%"
WATTAGE"1/16W"
MATERIAL"CHIP"
PACK_TYPE"0402LF"
PART_NUMBER"CS21002FB06"
CDS_LIB"pure_quanta"
LOCATION"R796"
$SEC"1"
CDS_SEC"1";
"A"
$PN"1"15;
"B"
$PN"2"54;
%"Q_CAP"
"1","(-1625,-75)","0","pure_quanta","I256";
;
TOLERANCE"10%"
VALUE"0.1UF"
MATERIAL"X7R"
PART_NUMBER"CH4104K1B00"
VOLTAGE"25V"
PACK_TYPE"0402"
CDS_LIB"pure_quanta"
LOCATION"C311"
$SEC"1"
CDS_SEC"1";
"B"
$PN"2"39;
"A"
$PN"1"54;
%"UNIVERSAL_GND"
"1","(-1625,-350)","0","logical_power","I257";
;
HDL_POWER"GND"
CDS_LIB"logical_power";
"A"39;
%"Q_CAP"
"1","(-1300,-1550)","0","pure_quanta","I259";
;
PACK_TYPE"0402"
MATERIAL"X7R"
PART_NUMBER"CH4104K1B00"
TOLERANCE"10%"
VOLTAGE"25V"
VALUE"0.1UF"
CDS_LIB"pure_quanta"
LOCATION"C314"
$SEC"1"
CDS_SEC"1";
"B"
$PN"2"40;
"A"
$PN"1"47;
%"Q_RES"
"2","(-1500,-1175)","2","pure_quanta","I261";
;
VALUE"2.87K"
TOLERANCE"1%"
WATTAGE"1/16W"
MATERIAL"CHIP"
PACK_TYPE"0402LF"
PART_NUMBER"CS22872FB03"
CDS_LIB"pure_quanta"
LOCATION"R797"
$SEC"1"
CDS_SEC"1";
"A"
$PN"1"20;
"B"
$PN"2"47;
%"Q_RES"
"2","(-1500,-1550)","2","pure_quanta","I262";
;
WATTAGE"1/16W"
TOLERANCE"1%"
MATERIAL"CHIP"
PACK_TYPE"0402LF"
PART_NUMBER"CS22002FB07"
VALUE"2K"
CDS_LIB"pure_quanta"
LOCATION"R798"
$SEC"1"
CDS_SEC"1";
"A"
$PN"1"47;
"B"
$PN"2"40;
%"UNIVERSAL_GND"
"1","(-1500,-1825)","0","logical_power","I263";
;
HDL_POWER"GND"
CDS_LIB"logical_power";
"A"40;
%"UNIVERSAL_POWER"
"1","(-1500,-975)","0","logical_power","I264";
;
HDL_POWER"PGPPA_BMC_AUX"
CDS_LIB"logical_power";
"A"20;
%"Q_RES"
"2","(650,-175)","0","pure_quanta","I289";
;
PART_NUMBER"CS42002FB05"
VALUE"200K"
PACK_TYPE"0402LF"
MATERIAL"CHIP"
WATTAGE"1/16W"
TOLERANCE"1%"
CDS_LIB"pure_quanta"
LOCATION"R777"
$SEC"1"
CDS_SEC"1";
"A"
$PN"1"86;
"B"
$PN"2"62;
%"UNIVERSAL_POWER"
"1","(2050,-300)","0","logical_power","I3";
;
HDL_POWER"P3V3_AUX"
CDS_LIB"logical_power";
"A"10;
%"UNIVERSAL_POWER"
"1","(4125,-500)","0","logical_power","I31";
;
HDL_POWER"P1V8_AUX"
CDS_LIB"logical_power";
"A"9;
%"Q_RES"
"1","(4125,3275)","0","pure_quanta","I318";
;
MATERIAL"CHIP"
VALUE"0"
PART_NUMBER"CS00002JB13"
PACK_TYPE"0402LF"
WATTAGE"1/16W"
TOLERANCE"5%"
CDS_LIB"pure_quanta"
LOCATION"R316"
$SEC"1"
CDS_SEC"1";
"B"
$PN"2"143;
"A"
$PN"1"156;
%"Q_RES"
"1","(4700,-650)","0","pure_quanta","I32";
;
VALUE"0"
MATERIAL"EMPTY"
PART_NUMBER"CS00002JB13"
PACK_TYPE"0402LF"
WATTAGE"1/16W"
TOLERANCE"5%"
CDS_LIB"pure_quanta"
LOCATION"R214"
$SEC"1"
CDS_SEC"1";
"B"
$PN"2"7;
"A"
$PN"1"9;
%"Q_RES"
"1","(-1300,2625)","0","pure_quanta","I320";
;
VALUE"33.2"
MATERIAL"CHIP"
TOLERANCE"1%"
PART_NUMBER"CS03322FB03"
PACK_TYPE"0402LF"
WATTAGE"1/16W"
CDS_LIB"pure_quanta"
LOCATION"R448"
$SEC"1"
CDS_SEC"1";
"B"
$PN"2"92;
"A"
$PN"1"76;
%"Q_RES"
"1","(-1300,2575)","0","pure_quanta","I321";
;
MATERIAL"CHIP"
VALUE"33.2"
TOLERANCE"1%"
PART_NUMBER"CS03322FB03"
PACK_TYPE"0402LF"
WATTAGE"1/16W"
CDS_LIB"pure_quanta"
LOCATION"R449"
$SEC"1"
CDS_SEC"1";
"B"
$PN"2"91;
"A"
$PN"1"77;
%"Q_RES"
"1","(-825,3525)","0","pure_quanta","I326";
;
MATERIAL"CHIP"
VALUE"33.2"
TOLERANCE"1%"
PART_NUMBER"CS03322FB03"
WATTAGE"1/16W"
CDS_LIB"pure_quanta"
PACK_TYPE"0402LF"
LOCATION"R489"
$SEC"1"
CDS_SEC"1";
"B"
$PN"2"96;
"A"
$PN"1"101;
%"UNIVERSAL_POWER"
"1","(4325,-100)","0","logical_power","I33";
;
HDL_POWER"P3V3_AUX"
CDS_LIB"logical_power";
"A"8;
%"Q_RES"
"1","(-825,3625)","0","pure_quanta","I330";
;
MATERIAL"CHIP"
VALUE"33.2"
TOLERANCE"1%"
PART_NUMBER"CS03322FB03"
WATTAGE"1/16W"
CDS_LIB"pure_quanta"
PACK_TYPE"0402LF"
LOCATION"R479"
$SEC"1"
CDS_SEC"1";
"B"
$PN"2"70;
"A"
$PN"1"102;
%"Q_RES"
"1","(4700,-350)","0","pure_quanta","I34";
;
VALUE"0"
MATERIAL"CHIP"
PART_NUMBER"CS00002JB13"
WATTAGE"1/16W"
PACK_TYPE"0402LF"
TOLERANCE"5%"
CDS_LIB"pure_quanta"
LOCATION"R213"
$SEC"1"
CDS_SEC"1";
"B"
$PN"2"7;
"A"
$PN"1"8;
%"Q_RES"
"1","(4025,3725)","2","pure_quanta","I345";
;
VALUE"33.2"
MATERIAL"CHIP"
TOLERANCE"1%"
PART_NUMBER"CS03322FB03"
PACK_TYPE"0402LF"
WATTAGE"1/16W"
CDS_LIB"pure_quanta"
LOCATION"R644"
$SEC"1"
CDS_SEC"1";
"B"
$PN"2"163;
"A"
$PN"1"133;
%"Q_RES"
"2","(-2650,4275)","0","pure_quanta","I346";
;
VALUE"4.7K"
TOLERANCE"1%"
MATERIAL"EMPTY"
PART_NUMBER"CS24702FB06"
PACK_TYPE"0402LF"
WATTAGE"1/16W"
CDS_LIB"pure_quanta"
LOCATION"R491"
$SEC"1"
CDS_SEC"1";
"A"
$PN"1"12;
"B"
$PN"2"104;
%"UNIVERSAL_GND"
"1","(5525,-800)","0","logical_power","I35";
;
HDL_POWER"GND"
CDS_LIB"logical_power";
"A"41;
%"AST2600A3GP"
"4","(1350,2900)","0","pure_quanta","I350";
;
MATERIAL"IC"
PART_NUMBER"AJ026000T06"
PART_TYPE"SMLF"
VALUE"AST2600A3-GP"
CDS_LIB"pure_quanta"
CDS_LMAN_SYM_OUTLINE"-750,1475,750,-1475"
NEEDS_NO_SIZE"TRUE"
LOCATION"U5"
$SEC"4"
CDS_SEC"4";
"CHASI# \B"
$PN"AB21"134;
"GPIOI1||MTDI2||RXD12"
$PN"A16"136;
"GPIOI0||MNTRST2||TXD12"
$PN"D17"139;
"GPIOI2||MTCK2||TXD13"
$PN"E17"138;
"GPIOI3||MTMS2||RXD13"
$PN"D16"137;
"GPIOI4||MTDO2"
$PN"C16"56;
"PECI"
$PN"AF16"114;
"PECIVDD"
$PN"AA18"150;
"USB2AV18"
$PN"K10"154;
"SSPRST# \B"
$PN"D7"124;
"GPIOP7||PWM15||HBLED#"
$PN"Y23"112;
"GPIOP6||PWM14"
$PN"AB24"111;
"GPIOP5||PWM13||THRUOUT2"
$PN"AB23"155;
"GPIOP4||PWM12||THRUIN2"
$PN"W23"156;
"GPIOP3||PWM11||THRUOUT1"
$PN"AA24"157;
"GPIOP2||PWM10||THRUIN1"
$PN"AA23"158;
"GPIOP1||PWM9||THRUOUT0"
$PN"W24"159;
"GPIOP0||PWM8||THRUIN0"
$PN"AB22"160;
"GPIOR7||TACH15"
$PN"U26"123;
"GPIOR6||TACH14"
$PN"W26"97;
"GPIOR5||TACH13"
$PN"T23"98;
"GPIOR4||TACH12"
$PN"U25"99;
"GPIOR3||TACH11"
$PN"V26"128;
"GPIOR2||TACH10"
$PN"V24"93;
"GPIOR1||TACH9"
$PN"U24"94;
"GPIOR0||TACH8"
$PN"V25"95;
"GPIOQ7||TACH7"
$PN"AA26"96;
"GPIOQ6||TACH6"
$PN"Y25"69;
"GPIOQ5||TACH5"
$PN"AC26"70;
"GPIOQ4||TACH4"
$PN"Y26"71;
"GPIOQ3||TACH3"
$PN"AB26"72;
"GPIOQ2||TACH2"
$PN"Y24"73;
"GPIOQ1||TACH1"
$PN"AB25"75;
"GPIOQ0||TACH0"
$PN"AA25"74;
"GPIOO7||PWM7"
$PN"AC23"110;
"GPIOO6||PWM6"
$PN"AC24"109;
"GPIOO5||PWM5"
$PN"AC22"161;
"GPIOO4||PWM4"
$PN"AD25"162;
"GPIOO3||PWM3"
$PN"AD24"163;
"GPIOO2||PWM2"
$PN"AD23"164;
"GPIOO1||PWM1"
$PN"AD22"0;
"GPIOO0||PWM0"
$PN"AD26"166;
"DDCDAT"
$PN"A8"167;
"DDCCLK"
$PN"B8"165;
"GPIOL7||VGAVS"
$PN"C14"108;
"GPIOL6||VGAHS"
$PN"B14"107;
"TMS||MTMS1"
$PN"A9"58;
"TDO||MTDO1"
$PN"C9"67;
"TDI||MTDI1"
$PN"D9"149;
"TCK||MTCK1"
$PN"B9"115;
"NTRST||MNTRST1"
$PN"F11"116;
"RSTIND# \B"
$PN"B7"125;
"CLKIN"
$PN"D10"59;
"EXTRST# \B"
$PN"B10"60;
"SRST# \B"
$PN"E10"61;
"ENTEST"
$PN"C10"126;
"ADC15||GPIU7||SALT16"
$PN"AC17"88;
"ADC14||GPIU6||SALT15"
$PN"AD16"117;
"ADC13||GPIU5||SALT14"
$PN"AA16"118;
"ADC12||GPIU4||SALT13"
$PN"AC16"89;
"ADC11||GPIU3||SALT12"
$PN"AE16"119;
"ADC10||GPIU2||SALT11"
$PN"AB17"90;
"ADC9||GPIU1||SALT10"
$PN"AA17"91;
"ADC8||GPIU0||SALT9"
$PN"AB16"92;
"ADC7||GPIT7"
$PN"AE18"105;
"ADC6||GPIT6"
$PN"AB18"106;
"ADC5||GPIT5"
$PN"AB19"68;
"ADC4||GPIT4"
$PN"AC19"57;
"ADC3||GPIT3"
$PN"AD19"120;
"ADC2||GPIT2"
$PN"AE19"121;
"ADC1||GPIT1"
$PN"AC18"100;
"ADC0||GPIT0"
$PN"AD20"122;
"USB2B_DP"
$PN"A6"151;
"USB2B_DN"
$PN"B6"113;
"USB2A_DP"
$PN"A4"153;
"USB2A_DN"
$PN"B4"152;
"USB2AV33"
$PN"J10"63;
"DACR"
$PN"AF21"174;
"DACG"
$PN"AE21"175;
"DACB"
$PN"AD21"173;
%"Q_RES"
"1","(-300,1975)","2","pure_quanta","I351";
;
TOLERANCE"5%"
MATERIAL"CHIP"
WATTAGE"1/16W"
VALUE"0"
PACK_TYPE"0402LF"
PART_NUMBER"CS00002JB13"
CDS_LIB"pure_quanta"
$LOCATION"R398"
CDS_LOCATION"R398"
$SEC"1"
CDS_SEC"1";
"B"
$PN"2"87;
"A"
$PN"1"56;
%"Q_RES"
"1","(3900,2975)","0","pure_quanta","I353";
;
VALUE"49.9"
MATERIAL"EMPTY"
WATTAGE"1/16W"
PART_NUMBER"CS04992FB07"
TOLERANCE"1%"
CDS_LIB"pure_quanta"
PACK_TYPE"0402LF"
$LOCATION"R441"
CDS_LOCATION"R441"
$SEC"1"
CDS_SEC"1";
"B"
$PN"2"27;
"A"
$PN"1"146;
%"Q_RES"
"1","(3900,3050)","0","pure_quanta","I354";
;
VALUE"49.9"
MATERIAL"EMPTY"
TOLERANCE"1%"
PART_NUMBER"CS04992FB07"
WATTAGE"1/16W"
CDS_LIB"pure_quanta"
PACK_TYPE"0402LF"
$LOCATION"R440"
CDS_LOCATION"R440"
$SEC"1"
CDS_SEC"1";
"B"
$PN"2"27;
"A"
$PN"1"145;
%"UNIVERSAL_GND"
"1","(4200,2900)","0","logical_power","I355";
;
HDL_POWER"GND"
CDS_LIB"logical_power";
"A"27;
%"Q_CAP"
"1","(5450,-525)","0","pure_quanta","I36";
;
PACK_TYPE"C0402"
MATERIAL"X6S"
TOLERANCE"10%"
VOLTAGE"25V"
VALUE"1UF"
CDS_LIB"pure_quanta"
PART_NUMBER"CH5104KEB02"
LOCATION"C38"
$SEC"1"
CDS_SEC"1";
"B"
$PN"2"41;
"A"
$PN"1"7;
%"Q_RES"
"1","(4125,3425)","0","pure_quanta","I367";
;
VALUE"0"
MATERIAL"CHIP"
CDS_LIB"pure_quanta"
PART_NUMBER"CS00002JB13"
WATTAGE"1/16W"
TOLERANCE"5%"
PACK_TYPE"0402LF"
$LOCATION"R804"
CDS_LOCATION"R804"
$SEC"1"
CDS_SEC"1";
"B"
$PN"2"140;
"A"
$PN"1"159;
%"Q_CAP"
"1","(3800,650)","0","pure_quanta","I368";
;
PART_NUMBER"CH5474KE906"
PACK_TYPE"C0603"
MATERIAL"X6S"
TOLERANCE"10%"
VOLTAGE"25V"
VALUE"4.7UF"
CDS_LIB"pure_quanta"
LOCATION"C40"
$SEC"1"
CDS_SEC"1";
"B"
$PN"2"43;
"A"
$PN"1"83;
%"Q_CAP"
"1","(5300,625)","0","pure_quanta","I369";
;
PACK_TYPE"C0603"
VOLTAGE"25V"
VALUE"4.7UF"
TOLERANCE"10%"
MATERIAL"X6S"
PART_NUMBER"CH5474KE906"
CDS_LIB"pure_quanta"
LOCATION"C44"
$SEC"1"
CDS_SEC"1";
"B"
$PN"2"44;
"A"
$PN"1"64;
%"Q_CAP"
"1","(5650,-525)","0","pure_quanta","I37";
;
PART_NUMBER"CH4104K1B00"
PACK_TYPE"0402"
TOLERANCE"10%"
VOLTAGE"25V"
VALUE"0.1UF"
MATERIAL"X7R"
CDS_LIB"pure_quanta"
LOCATION"C39"
$SEC"1"
CDS_SEC"1";
"B"
$PN"2"41;
"A"
$PN"1"7;
%"UNIVERSAL_POWER"
"1","(5900,-100)","0","logical_power","I38";
;
HDL_POWER"P3V3_P1V8_SD2VDD"
CDS_LIB"logical_power";
"A"7;
%"Q_RES"
"1","(3200,1525)","0","pure_quanta","I387";
;
PACK_TYPE"0402LF"
VALUE"0"
MATERIAL"CHIP"
PART_NUMBER"CS00002JB13"
TOLERANCE"5%"
WATTAGE"1/16W"
CDS_LIB"pure_quanta"
$LOCATION"R853"
CDS_LOCATION"R853"
$SEC"1"
CDS_SEC"1";
"B"
$PN"2"135;
"A"
$PN"1"134;
%"Q_RES"
"1","(3125,2325)","0","pure_quanta","I389";
;
MATERIAL"CHIP"
VALUE"49.9"
CDS_LIB"pure_quanta"
TOLERANCE"1%"
PART_NUMBER"CS04992FB07"
PACK_TYPE"0402LF"
WATTAGE"1/16W"
LOCATION"R216"
$SEC"1"
CDS_SEC"1";
"B"
$PN"2"129;
"A"
$PN"1"114;
%"OSC4_7X25000018"
"1","(575,450)","0","pure_quanta","I39";
;
MATERIAL"MISC"
PART_TYPE"SMLF"
PART_NUMBER"BF625000023"
VALUE"25MHZ"
CDS_LIB"pure_quanta"
PIN_NAMES_ROTATE"True"
CDS_LMAN_SYM_OUTLINE"-175,125,175,-125"
LOCATION"OSC1"
$SEC"1"
CDS_SEC"1";
"VDD"
$PN"4"13;
"OUT"
$PN"3"49;
"GND"
$PN"2"42;
"OE"
$PN"1"51;
%"Q_RES"
"1","(4425,3900)","0","pure_quanta","I391";
;
MATERIAL"CHIP"
VALUE"4.7K"
CDS_LIB"pure_quanta"
PART_NUMBER"CS24702FB06"
WATTAGE"1/16W"
TOLERANCE"1%"
PACK_TYPE"0402LF"
$LOCATION"R462"
CDS_LOCATION"R462"
$SEC"1"
CDS_SEC"1";
"B"
$PN"2"132;
"A"
$PN"1"5;
%"74LVC1G08GW"
"1","(5225,1625)","0","pure_quanta","I393";
;
PART_NUMBER"ALVC1G08009"
MATERIAL"IC"
VALUE"74LVC1G08GW"
PACK_TYPE"SM"
NEEDS_NO_SIZE"TRUE"
CDS_LIB"pure_quanta"
$LOCATION"U15"
CDS_LOCATION"U15"
$SEC"1"
CDS_SEC"1";
"VCC"
$PN"5"22;
"Y"
$PN"4"66;
"B"
$PN"1"84;
"A"
$PN"2"50;
"GND"
$PN"3"23;
%"UNIVERSAL_GND"
"1","(5575,1850)","0","logical_power","I396";
;
CDS_LIB"logical_power"
HDL_POWER"GND";
"A"24;
%"VCCAUX15"
"1","(5175,2275)","0","logical_power","I397";
;
HDL_POWER"P3V3_AUX"
CDS_LIB"logical_power";
"A"22;
%"Q_CAP"
"1","(5575,2025)","2","pure_quanta","I398";
;
TOLERANCE"10%"
VOLTAGE"25V"
PACK_TYPE"0402"
MATERIAL"X7R"
PART_NUMBER"CH4104K1B00"
VALUE"0.1UF"
CDS_LIB"pure_quanta"
$LOCATION"C26"
CDS_LOCATION"C26"
$SEC"1"
CDS_SEC"1";
"B"
$PN"2"24;
"A"
$PN"1"22;
%"UNIVERSAL_GND"
"1","(5175,1275)","0","logical_power","I399";
;
CDS_LIB"logical_power"
HDL_POWER"GND";
"A"23;
%"Q_RES"
"1","(2425,-550)","0","pure_quanta","I4";
;
WATTAGE"1/16W"
MATERIAL"CHIP"
PART_NUMBER"CS00002JB13"
VALUE"0"
PACK_TYPE"0402LF"
TOLERANCE"5%"
CDS_LIB"pure_quanta"
LOCATION"R207"
$SEC"1"
CDS_SEC"1";
"B"
$PN"2"3;
"A"
$PN"1"10;
%"UNIVERSAL_GND"
"1","(1075,175)","0","logical_power","I40";
;
HDL_POWER"GND"
CDS_LIB"logical_power";
"A"42;
%"Q_RES"
"1","(-725,4025)","0","pure_quanta","I404";
;
MATERIAL"CHIP"
VALUE"33.2"
WATTAGE"1/16W"
PACK_TYPE"0402LF"
PART_NUMBER"CS03322FB03"
TOLERANCE"1%"
CDS_LIB"pure_quanta"
LOCATION"R585"
$SEC"1"
CDS_SEC"1";
"B"
$PN"2"125;
"A"
$PN"1"127;
%"Q_RES"
"1","(4100,3550)","0","pure_quanta","I405";
;
VALUE"100"
MATERIAL"CHIP"
PART_NUMBER"CS11002FB07"
CDS_LIB"pure_quanta"
WATTAGE"1/16W"
TOLERANCE"1%"
PACK_TYPE"0402LF"
LOCATION"R225"
$SEC"1"
CDS_SEC"1";
"B"
$PN"2"141;
"A"
$PN"1"160;
%"Q_RES"
"1","(4125,3375)","0","pure_quanta","I406";
;
VALUE"100"
MATERIAL"CHIP"
PART_NUMBER"CS11002FB07"
WATTAGE"1/16W"
TOLERANCE"1%"
PACK_TYPE"0402LF"
CDS_LIB"pure_quanta"
LOCATION"R565"
$SEC"1"
CDS_SEC"1";
"B"
$PN"2"142;
"A"
$PN"1"158;
%"Q_RES"
"1","(1750,525)","0","pure_quanta","I42";
;
PACK_TYPE"0402LF"
MATERIAL"CHIP"
TOLERANCE"1%"
PART_NUMBER"CS03322FB03"
VALUE"33.2"
WATTAGE"1/16W"
CDS_LIB"pure_quanta"
LOCATION"R215"
$SEC"1"
CDS_SEC"1";
"B"
$PN"2"85;
"A"
$PN"1"49;
%"UNIVERSAL_GND"
"1","(-2250,3825)","0","logical_power","I46";
;
HDL_POWER"GND"
CDS_LIB"logical_power";
"A"25;
%"Q_RES"
"1","(-1850,3975)","0","pure_quanta","I47";
;
PART_NUMBER"CS21002FB06"
PACK_TYPE"0402LF"
WATTAGE"1/16W"
MATERIAL"CHIP"
TOLERANCE"1%"
VALUE"1K"
CDS_LIB"pure_quanta"
SEC_TYPE"0402LF"
LOCATION"R210"
SEC"1";
"B"
$PN"2"126;
"A"
$PN"1"25;
%"Q_RES"
"2","(-1025,4350)","2","pure_quanta","I51";
;
MATERIAL"CHIP"
WATTAGE"1/16W"
TOLERANCE"1%"
VALUE"10K"
PART_NUMBER"CS31002FB08"
PACK_TYPE"0402LF"
CDS_LIB"pure_quanta"
LOCATION"R211"
$SEC"1"
CDS_SEC"1";
"A"
$PN"1"11;
"B"
$PN"2"124;
%"UNIVERSAL_POWER"
"1","(-1025,4550)","0","logical_power","I52";
;
HDL_POWER"P3V3_RGM"
CDS_LIB"logical_power";
"A"11;
%"UNIVERSAL_POWER"
"1","(3200,900)","0","logical_power","I64";
;
HDL_POWER"P1V8_AUX"
CDS_LIB"logical_power";
"A"2;
%"Q_INDUCTOR"
"1","(3500,850)","0","pure_quanta","I65";
;
MATERIAL"IND"
PACK_TYPE"SMLF"
VALUE"BLM18PG121SN1D/2000MA"
PART_NUMBER"CX8PG121009"
NEEDS_NO_SIZE"TRUE"
CDS_LIB"pure_quanta"
LOCATION"L3"
$SEC"1"
CDS_SEC"1";
"1"
$PN"1"2;
"2"
$PN"2"83;
%"UNIVERSAL_GND"
"1","(3875,375)","0","logical_power","I66";
;
HDL_POWER"GND"
CDS_LIB"logical_power";
"A"43;
%"Q_CAP"
"1","(4000,650)","0","pure_quanta","I68";
;
VALUE"0.1UF"
PART_NUMBER"CH4104K1B00"
PACK_TYPE"0402"
MATERIAL"X7R"
TOLERANCE"10%"
VOLTAGE"25V"
CDS_LIB"pure_quanta"
LOCATION"C41"
$SEC"1"
CDS_SEC"1";
"B"
$PN"2"43;
"A"
$PN"1"83;
%"UNIVERSAL_POWER"
"1","(4700,875)","0","logical_power","I81";
;
HDL_POWER"P3V3_AUX"
CDS_LIB"logical_power";
"A"6;
%"Q_INDUCTOR"
"1","(5000,825)","0","pure_quanta","I82";
;
MATERIAL"IND"
PART_NUMBER"CX8PG121009"
PACK_TYPE"SMLF"
VALUE"BLM18PG121SN1D/2000MA"
NEEDS_NO_SIZE"TRUE"
CDS_LIB"pure_quanta"
LOCATION"L4"
$SEC"1"
CDS_SEC"1";
"1"
$PN"1"6;
"2"
$PN"2"64;
%"UNIVERSAL_GND"
"1","(5375,350)","0","logical_power","I87";
;
HDL_POWER"GND"
CDS_LIB"logical_power";
"A"44;
%"Q_CAP"
"1","(5500,625)","0","pure_quanta","I89";
;
VOLTAGE"25V"
MATERIAL"X7R"
TOLERANCE"10%"
PACK_TYPE"0402"
VALUE"0.1UF"
PART_NUMBER"CH4104K1B00"
CDS_LIB"pure_quanta"
LOCATION"C45"
$SEC"1"
CDS_SEC"1";
"B"
$PN"2"44;
"A"
$PN"1"64;
%"Q_RES"
"1","(3300,2825)","0","pure_quanta","I92";
;
VALUE"0"
MATERIAL"CHIP"
CDS_LIB"pure_quanta"
TOLERANCE"5%"
WATTAGE"1/16W"
PACK_TYPE"0402LF"
PART_NUMBER"CS00002JB13"
LOCATION"R217"
$SEC"1"
CDS_SEC"1";
"B"
$PN"2"145;
"A"
$PN"1"153;
%"Q_RES"
"1","(3300,2775)","0","pure_quanta","I93";
;
VALUE"0"
MATERIAL"CHIP"
CDS_LIB"pure_quanta"
TOLERANCE"5%"
WATTAGE"1/16W"
PACK_TYPE"0402LF"
PART_NUMBER"CS00002JB13"
LOCATION"R218"
$SEC"1"
CDS_SEC"1";
"B"
$PN"2"146;
"A"
$PN"1"152;
END.
